(kicad_pcb
	(version 20260206)
	(generator "pcbnew")
	(generator_version "10.0")
	(general
		(thickness 1.6)
		(legacy_teardrops no)
	)
	(paper "A4")
	(title_block
		(title "12092022_DA0F0TMDCD0_F0T_Management_Board_D_brd_V3_OCP.brd")
		(comment 1 "Grand Teton / footprints 306-311 of 1440")
	)
	(layers
		(0 "F.Cu" signal "TOP")
		(4 "In1.Cu" signal "GND")
		(6 "In2.Cu" signal "IN1")
		(8 "In3.Cu" signal "GND1")
		(10 "In4.Cu" signal "IN2")
		(12 "In5.Cu" signal "VCC")
		(14 "In6.Cu" signal "VCC1")
		(16 "In7.Cu" signal "IN3")
		(18 "In8.Cu" signal "GND2")
		(20 "In9.Cu" signal "IN4")
		(22 "In10.Cu" signal "GND3")
		(2 "B.Cu" signal "BOTTOM")
		(9 "F.Adhes" user "F.Adhesive")
		(11 "B.Adhes" user "B.Adhesive")
		(13 "F.Paste" user "Package Geometry/Pastemask Top")
		(15 "B.Paste" user "Package Geometry/Pastemask Bottom")
		(5 "F.SilkS" user "Ref Des/Silkscreen Top")
		(7 "B.SilkS" user "Ref Des/Silkscreen Bottom")
		(1 "F.Mask" user "Board Geometry/Soldermask Top")
		(3 "B.Mask" user "Board Geometry/Soldermask Bottom")
		(17 "Dwgs.User" user "User.Drawings")
		(19 "Cmts.User" user "User.Comments")
		(21 "Eco1.User" user "User.Eco1")
		(23 "Eco2.User" user "User.Eco2")
		(25 "Edge.Cuts" user "Board Geometry/Outline")
		(27 "Margin" user)
		(31 "F.CrtYd" user "Package Geometry/Place Bound Top")
		(29 "B.CrtYd" user "Package Geometry/Place Bound Bottom")
		(35 "F.Fab" user "Ref Des/Assembly Top")
		(33 "B.Fab" user "Ref Des/Assembly Bottom")
	)
	(footprint ""
		(layer "F.Cu")
		(at 25.5016 -33.909 90)
		(property "Reference" "R277"
			(at 0 0 90)
			(layer "F.SilkS")
			(hide yes)
			(effects
				(font
					(size 1.27 1.27)
				)
			)
		)
		(property "Value" ""
			(at 0 0 90)
			(layer "F.Fab")
			(effects
				(font
					(size 1.27 1.27)
				)
			)
		)
		(duplicate_pad_numbers_are_jumpers no)
		(fp_line
			(start 0.7874 -0.4064)
			(end 0.7874 0.4064)
			(stroke
				(width 0.1524)
				(type default)
			)
			(layer "F.SilkS")
		)
		(fp_line
			(start -0.7874 -0.4064)
			(end 0.7874 -0.4064)
			(stroke
				(width 0.1524)
				(type default)
			)
			(layer "F.SilkS")
		)
		(fp_line
			(start 0.7874 0.4064)
			(end -0.7874 0.4064)
			(stroke
				(width 0.1524)
				(type default)
			)
			(layer "F.SilkS")
		)
		(fp_line
			(start -0.7874 0.4064)
			(end -0.7874 -0.4064)
			(stroke
				(width 0.1524)
				(type default)
			)
			(layer "F.SilkS")
		)
		(fp_line
			(start -0.12065 -0.305054)
			(end -0.12065 -0.2794)
			(stroke
				(width 0.1)
				(type default)
			)
			(layer "F.Fab")
		)
		(fp_line
			(start -0.67945 -0.305054)
			(end -0.12065 -0.305054)
			(stroke
				(width 0.1)
				(type default)
			)
			(layer "F.Fab")
		)
		(fp_line
			(start 0.67945 -0.3048)
			(end 0.67945 0.3048)
			(stroke
				(width 0.1)
				(type default)
			)
			(layer "F.Fab")
		)
		(fp_line
			(start 0.12065 -0.3048)
			(end 0.67945 -0.3048)
			(stroke
				(width 0.1)
				(type default)
			)
			(layer "F.Fab")
		)
		(fp_line
			(start 0.12065 -0.2794)
			(end 0.12065 -0.3048)
			(stroke
				(width 0.1)
				(type default)
			)
			(layer "F.Fab")
		)
		(fp_line
			(start -0.12065 -0.2794)
			(end 0.12065 -0.2794)
			(stroke
				(width 0.1)
				(type default)
			)
			(layer "F.Fab")
		)
		(fp_line
			(start 0.120396 0.2794)
			(end -0.12065 0.2794)
			(stroke
				(width 0.1)
				(type default)
			)
			(layer "F.Fab")
		)
		(fp_line
			(start -0.12065 0.2794)
			(end -0.12065 0.3048)
			(stroke
				(width 0.1)
				(type default)
			)
			(layer "F.Fab")
		)
		(fp_line
			(start 0.67945 0.3048)
			(end 0.120396 0.3048)
			(stroke
				(width 0.1)
				(type default)
			)
			(layer "F.Fab")
		)
		(fp_line
			(start 0.120396 0.3048)
			(end 0.120396 0.2794)
			(stroke
				(width 0.1)
				(type default)
			)
			(layer "F.Fab")
		)
		(fp_line
			(start -0.12065 0.3048)
			(end -0.67945 0.3048)
			(stroke
				(width 0.1)
				(type default)
			)
			(layer "F.Fab")
		)
		(fp_line
			(start -0.67945 0.3048)
			(end -0.67945 -0.305054)
			(stroke
				(width 0.1)
				(type default)
			)
			(layer "F.Fab")
		)
		(pad "1" smd circle
			(at -0.40005 0 90)
			(size 0 0)
			(layers "F.Cu" "F.Mask" "F.Paste")
			(net "PWRGD_P1V0_AUX_R")
		)
		(pad "2" smd circle
			(at 0.40005 0 90)
			(size 0 0)
			(layers "F.Cu" "F.Mask" "F.Paste")
			(net "PWRGD_P1V0_AUX")
		)
	)
	(footprint ""
		(layer "F.Cu")
		(at 41.859454 -65.776094 -90)
		(property "Reference" "R184"
			(at 0 0 270)
			(layer "F.SilkS")
			(hide yes)
			(effects
				(font
					(size 1.27 1.27)
				)
			)
		)
		(property "Value" ""
			(at 0 0 270)
			(layer "F.Fab")
			(effects
				(font
					(size 1.27 1.27)
				)
			)
		)
		(duplicate_pad_numbers_are_jumpers no)
		(fp_line
			(start -0.7874 0.4064)
			(end -0.7874 -0.4064)
			(stroke
				(width 0.1524)
				(type default)
			)
			(layer "F.SilkS")
		)
		(fp_line
			(start 0.7874 0.4064)
			(end -0.7874 0.4064)
			(stroke
				(width 0.1524)
				(type default)
			)
			(layer "F.SilkS")
		)
		(fp_line
			(start -0.7874 -0.4064)
			(end 0.7874 -0.4064)
			(stroke
				(width 0.1524)
				(type default)
			)
			(layer "F.SilkS")
		)
		(fp_line
			(start 0.7874 -0.4064)
			(end 0.7874 0.4064)
			(stroke
				(width 0.1524)
				(type default)
			)
			(layer "F.SilkS")
		)
		(fp_line
			(start -0.67945 0.3048)
			(end -0.67945 -0.305054)
			(stroke
				(width 0.1)
				(type default)
			)
			(layer "F.Fab")
		)
		(fp_line
			(start -0.12065 0.3048)
			(end -0.67945 0.3048)
			(stroke
				(width 0.1)
				(type default)
			)
			(layer "F.Fab")
		)
		(fp_line
			(start 0.120396 0.3048)
			(end 0.120396 0.2794)
			(stroke
				(width 0.1)
				(type default)
			)
			(layer "F.Fab")
		)
		(fp_line
			(start 0.67945 0.3048)
			(end 0.120396 0.3048)
			(stroke
				(width 0.1)
				(type default)
			)
			(layer "F.Fab")
		)
		(fp_line
			(start -0.12065 0.2794)
			(end -0.12065 0.3048)
			(stroke
				(width 0.1)
				(type default)
			)
			(layer "F.Fab")
		)
		(fp_line
			(start 0.120396 0.2794)
			(end -0.12065 0.2794)
			(stroke
				(width 0.1)
				(type default)
			)
			(layer "F.Fab")
		)
		(fp_line
			(start -0.12065 -0.2794)
			(end 0.12065 -0.2794)
			(stroke
				(width 0.1)
				(type default)
			)
			(layer "F.Fab")
		)
		(fp_line
			(start 0.12065 -0.2794)
			(end 0.12065 -0.3048)
			(stroke
				(width 0.1)
				(type default)
			)
			(layer "F.Fab")
		)
		(fp_line
			(start 0.12065 -0.3048)
			(end 0.67945 -0.3048)
			(stroke
				(width 0.1)
				(type default)
			)
			(layer "F.Fab")
		)
		(fp_line
			(start 0.67945 -0.3048)
			(end 0.67945 0.3048)
			(stroke
				(width 0.1)
				(type default)
			)
			(layer "F.Fab")
		)
		(fp_line
			(start -0.67945 -0.305054)
			(end -0.12065 -0.305054)
			(stroke
				(width 0.1)
				(type default)
			)
			(layer "F.Fab")
		)
		(fp_line
			(start -0.12065 -0.305054)
			(end -0.12065 -0.2794)
			(stroke
				(width 0.1)
				(type default)
			)
			(layer "F.Fab")
		)
		(pad "1" smd circle
			(at -0.40005 0 270)
			(size 0 0)
			(layers "F.Cu" "F.Mask" "F.Paste")
			(net "I3C1_SPD_SCL")
		)
		(pad "2" smd circle
			(at 0.40005 0 270)
			(size 0 0)
			(layers "F.Cu" "F.Mask" "F.Paste")
			(net "I3C1_SCL_R")
		)
	)
	(footprint ""
		(layer "F.Cu")
		(at 63.654432 -66.926968 180)
		(property "Reference" "L17"
			(at 0 0 180)
			(layer "F.SilkS")
			(hide yes)
			(effects
				(font
					(size 1.27 1.27)
				)
			)
		)
		(property "Value" ""
			(at 0 0 180)
			(layer "F.Fab")
			(effects
				(font
					(size 1.27 1.27)
				)
			)
		)
		(duplicate_pad_numbers_are_jumpers no)
		(fp_line
			(start 1.27 0.5842)
			(end 1.27 -0.5842)
			(stroke
				(width 0.1524)
				(type default)
			)
			(layer "F.SilkS")
		)
		(fp_line
			(start 1.27 0.5842)
			(end -1.27 0.5842)
			(stroke
				(width 0.1524)
				(type default)
			)
			(layer "F.SilkS")
		)
		(fp_line
			(start 0.127 0.5842)
			(end 0.127 -0.5842)
			(stroke
				(width 0.1524)
				(type default)
			)
			(layer "F.SilkS")
		)
		(fp_line
			(start -0.127 0.5842)
			(end -0.127 -0.5842)
			(stroke
				(width 0.1524)
				(type default)
			)
			(layer "F.SilkS")
		)
		(fp_line
			(start -1.27 0.5842)
			(end -1.27 -0.5842)
			(stroke
				(width 0.1524)
				(type default)
			)
			(layer "F.SilkS")
		)
		(fp_line
			(start -1.27 -0.5588)
			(end -1.27 -0.5842)
			(stroke
				(width 0.1524)
				(type default)
			)
			(layer "F.SilkS")
		)
		(fp_line
			(start -1.27 -0.5842)
			(end 1.27 -0.5842)
			(stroke
				(width 0.1524)
				(type default)
			)
			(layer "F.SilkS")
		)
		(fp_line
			(start 1.1938 0.4064)
			(end 0.9144 0.4064)
			(stroke
				(width 0.1)
				(type default)
			)
			(layer "F.Fab")
		)
		(fp_line
			(start 1.1938 -0.406654)
			(end 1.1938 0.4064)
			(stroke
				(width 0.1)
				(type default)
			)
			(layer "F.Fab")
		)
		(fp_line
			(start 0.9144 0.508)
			(end -0.9144 0.508)
			(stroke
				(width 0.1)
				(type default)
			)
			(layer "F.Fab")
		)
		(fp_line
			(start 0.9144 0.4064)
			(end 0.9144 0.508)
			(stroke
				(width 0.1)
				(type default)
			)
			(layer "F.Fab")
		)
		(fp_line
			(start 0.9144 -0.406654)
			(end 1.1938 -0.406654)
			(stroke
				(width 0.1)
				(type default)
			)
			(layer "F.Fab")
		)
		(fp_line
			(start 0.9144 -0.508)
			(end 0.9144 -0.406654)
			(stroke
				(width 0.1)
				(type default)
			)
			(layer "F.Fab")
		)
		(fp_line
			(start -0.9144 0.508)
			(end -0.9144 0.406654)
			(stroke
				(width 0.1)
				(type default)
			)
			(layer "F.Fab")
		)
		(fp_line
			(start -0.9144 0.406654)
			(end -1.194308 0.406654)
			(stroke
				(width 0.1)
				(type default)
			)
			(layer "F.Fab")
		)
		(fp_line
			(start -0.9144 -0.406654)
			(end -0.9144 -0.508)
			(stroke
				(width 0.1)
				(type default)
			)
			(layer "F.Fab")
		)
		(fp_line
			(start -0.9144 -0.508)
			(end 0.9144 -0.508)
			(stroke
				(width 0.1)
				(type default)
			)
			(layer "F.Fab")
		)
		(fp_line
			(start -1.194308 0.406654)
			(end -1.194308 -0.406654)
			(stroke
				(width 0.1)
				(type default)
			)
			(layer "F.Fab")
		)
		(fp_line
			(start -1.194308 -0.406654)
			(end -0.9144 -0.406654)
			(stroke
				(width 0.1)
				(type default)
			)
			(layer "F.Fab")
		)
		(pad "1" smd rect
			(at -0.7366 0 90)
			(size 0.7112 0.8128)
			(layers "F.Cu" "F.Mask" "F.Paste")
			(net "PGPPA_BMC_AUX_L")
		)
		(pad "2" smd rect
			(at 0.7366 0 90)
			(size 0.7112 0.8128)
			(layers "F.Cu" "F.Mask" "F.Paste")
			(net "PGPPA_BMC_AUX")
		)
	)
	(footprint ""
		(layer "F.Cu")
		(at 47.6377 -66.35496 -90)
		(property "Reference" "R461"
			(at 0 0 270)
			(layer "F.SilkS")
			(hide yes)
			(effects
				(font
					(size 1.27 1.27)
				)
			)
		)
		(property "Value" ""
			(at 0 0 270)
			(layer "F.Fab")
			(effects
				(font
					(size 1.27 1.27)
				)
			)
		)
		(duplicate_pad_numbers_are_jumpers no)
		(fp_line
			(start -0.7874 0.4064)
			(end -0.7874 -0.4064)
			(stroke
				(width 0.1524)
				(type default)
			)
			(layer "F.SilkS")
		)
		(fp_line
			(start 0.7874 0.4064)
			(end -0.7874 0.4064)
			(stroke
				(width 0.1524)
				(type default)
			)
			(layer "F.SilkS")
		)
		(fp_line
			(start -0.7874 -0.4064)
			(end 0.7874 -0.4064)
			(stroke
				(width 0.1524)
				(type default)
			)
			(layer "F.SilkS")
		)
		(fp_line
			(start 0.7874 -0.4064)
			(end 0.7874 0.4064)
			(stroke
				(width 0.1524)
				(type default)
			)
			(layer "F.SilkS")
		)
		(fp_line
			(start -0.67945 0.3048)
			(end -0.67945 -0.305054)
			(stroke
				(width 0.1)
				(type default)
			)
			(layer "F.Fab")
		)
		(fp_line
			(start -0.12065 0.3048)
			(end -0.67945 0.3048)
			(stroke
				(width 0.1)
				(type default)
			)
			(layer "F.Fab")
		)
		(fp_line
			(start 0.120396 0.3048)
			(end 0.120396 0.2794)
			(stroke
				(width 0.1)
				(type default)
			)
			(layer "F.Fab")
		)
		(fp_line
			(start 0.67945 0.3048)
			(end 0.120396 0.3048)
			(stroke
				(width 0.1)
				(type default)
			)
			(layer "F.Fab")
		)
		(fp_line
			(start -0.12065 0.2794)
			(end -0.12065 0.3048)
			(stroke
				(width 0.1)
				(type default)
			)
			(layer "F.Fab")
		)
		(fp_line
			(start 0.120396 0.2794)
			(end -0.12065 0.2794)
			(stroke
				(width 0.1)
				(type default)
			)
			(layer "F.Fab")
		)
		(fp_line
			(start -0.12065 -0.2794)
			(end 0.12065 -0.2794)
			(stroke
				(width 0.1)
				(type default)
			)
			(layer "F.Fab")
		)
		(fp_line
			(start 0.12065 -0.2794)
			(end 0.12065 -0.3048)
			(stroke
				(width 0.1)
				(type default)
			)
			(layer "F.Fab")
		)
		(fp_line
			(start 0.12065 -0.3048)
			(end 0.67945 -0.3048)
			(stroke
				(width 0.1)
				(type default)
			)
			(layer "F.Fab")
		)
		(fp_line
			(start 0.67945 -0.3048)
			(end 0.67945 0.3048)
			(stroke
				(width 0.1)
				(type default)
			)
			(layer "F.Fab")
		)
		(fp_line
			(start -0.67945 -0.305054)
			(end -0.12065 -0.305054)
			(stroke
				(width 0.1)
				(type default)
			)
			(layer "F.Fab")
		)
		(fp_line
			(start -0.12065 -0.305054)
			(end -0.12065 -0.2794)
			(stroke
				(width 0.1)
				(type default)
			)
			(layer "F.Fab")
		)
		(pad "1" smd circle
			(at -0.40005 0 270)
			(size 0 0)
			(layers "F.Cu" "F.Mask" "F.Paste")
			(net "BMC_ID_BEEP_SEL")
		)
		(pad "2" smd circle
			(at 0.40005 0 270)
			(size 0 0)
			(layers "F.Cu" "F.Mask" "F.Paste")
			(net "BMC_ID_BEEP_SEL_R1")
		)
	)
	(footprint ""
		(layer "F.Cu")
		(at 73.787 -25.5016 180)
		(property "Reference" "R601"
			(at 0 0 180)
			(layer "F.SilkS")
			(hide yes)
			(effects
				(font
					(size 1.27 1.27)
				)
			)
		)
		(property "Value" ""
			(at 0 0 180)
			(layer "F.Fab")
			(effects
				(font
					(size 1.27 1.27)
				)
			)
		)
		(duplicate_pad_numbers_are_jumpers no)
		(fp_line
			(start 0.7874 0.4064)
			(end -0.7874 0.4064)
			(stroke
				(width 0.1524)
				(type default)
			)
			(layer "F.SilkS")
		)
		(fp_line
			(start 0.7874 -0.4064)
			(end 0.7874 0.4064)
			(stroke
				(width 0.1524)
				(type default)
			)
			(layer "F.SilkS")
		)
		(fp_line
			(start -0.7874 0.4064)
			(end -0.7874 -0.4064)
			(stroke
				(width 0.1524)
				(type default)
			)
			(layer "F.SilkS")
		)
		(fp_line
			(start -0.7874 -0.4064)
			(end 0.7874 -0.4064)
			(stroke
				(width 0.1524)
				(type default)
			)
			(layer "F.SilkS")
		)
		(fp_line
			(start 0.67945 0.3048)
			(end 0.120396 0.3048)
			(stroke
				(width 0.1)
				(type default)
			)
			(layer "F.Fab")
		)
		(fp_line
			(start 0.67945 -0.3048)
			(end 0.67945 0.3048)
			(stroke
				(width 0.1)
				(type default)
			)
			(layer "F.Fab")
		)
		(fp_line
			(start 0.12065 -0.2794)
			(end 0.12065 -0.3048)
			(stroke
				(width 0.1)
				(type default)
			)
			(layer "F.Fab")
		)
		(fp_line
			(start 0.12065 -0.3048)
			(end 0.67945 -0.3048)
			(stroke
				(width 0.1)
				(type default)
			)
			(layer "F.Fab")
		)
		(fp_line
			(start 0.120396 0.3048)
			(end 0.120396 0.2794)
			(stroke
				(width 0.1)
				(type default)
			)
			(layer "F.Fab")
		)
		(fp_line
			(start 0.120396 0.2794)
			(end -0.12065 0.2794)
			(stroke
				(width 0.1)
				(type default)
			)
			(layer "F.Fab")
		)
		(fp_line
			(start -0.12065 0.3048)
			(end -0.67945 0.3048)
			(stroke
				(width 0.1)
				(type default)
			)
			(layer "F.Fab")
		)
		(fp_line
			(start -0.12065 0.2794)
			(end -0.12065 0.3048)
			(stroke
				(width 0.1)
				(type default)
			)
			(layer "F.Fab")
		)
		(fp_line
			(start -0.12065 -0.2794)
			(end 0.12065 -0.2794)
			(stroke
				(width 0.1)
				(type default)
			)
			(layer "F.Fab")
		)
		(fp_line
			(start -0.12065 -0.305054)
			(end -0.12065 -0.2794)
			(stroke
				(width 0.1)
				(type default)
			)
			(layer "F.Fab")
		)
		(fp_line
			(start -0.67945 0.3048)
			(end -0.67945 -0.305054)
			(stroke
				(width 0.1)
				(type default)
			)
			(layer "F.Fab")
		)
		(fp_line
			(start -0.67945 -0.305054)
			(end -0.12065 -0.305054)
			(stroke
				(width 0.1)
				(type default)
			)
			(layer "F.Fab")
		)
		(pad "1" smd circle
			(at -0.40005 0 180)
			(size 0 0)
			(layers "F.Cu" "F.Mask" "F.Paste")
			(net "LED_POSTCODE_3")
		)
		(pad "2" smd circle
			(at 0.40005 0 180)
			(size 0 0)
			(layers "F.Cu" "F.Mask" "F.Paste")
			(net "LED_POSTCODE_3_R")
		)
	)
	(footprint ""
		(layer "F.Cu")
		(at 33.909 -36.195 90)
		(property "Reference" "R751"
			(at 0 0 90)
			(layer "F.SilkS")
			(hide yes)
			(effects
				(font
					(size 1.27 1.27)
				)
			)
		)
		(property "Value" ""
			(at 0 0 90)
			(layer "F.Fab")
			(effects
				(font
					(size 1.27 1.27)
				)
			)
		)
		(duplicate_pad_numbers_are_jumpers no)
		(fp_line
			(start 0.7874 -0.4064)
			(end 0.7874 0.4064)
			(stroke
				(width 0.1524)
				(type default)
			)
			(layer "F.SilkS")
		)
		(fp_line
			(start -0.7874 -0.4064)
			(end 0.7874 -0.4064)
			(stroke
				(width 0.1524)
				(type default)
			)
			(layer "F.SilkS")
		)
		(fp_line
			(start 0.7874 0.4064)
			(end -0.7874 0.4064)
			(stroke
				(width 0.1524)
				(type default)
			)
			(layer "F.SilkS")
		)
		(fp_line
			(start -0.7874 0.4064)
			(end -0.7874 -0.4064)
			(stroke
				(width 0.1524)
				(type default)
			)
			(layer "F.SilkS")
		)
		(fp_line
			(start -0.12065 -0.305054)
			(end -0.12065 -0.2794)
			(stroke
				(width 0.1)
				(type default)
			)
			(layer "F.Fab")
		)
		(fp_line
			(start -0.67945 -0.305054)
			(end -0.12065 -0.305054)
			(stroke
				(width 0.1)
				(type default)
			)
			(layer "F.Fab")
		)
		(fp_line
			(start 0.67945 -0.3048)
			(end 0.67945 0.3048)
			(stroke
				(width 0.1)
				(type default)
			)
			(layer "F.Fab")
		)
		(fp_line
			(start 0.12065 -0.3048)
			(end 0.67945 -0.3048)
			(stroke
				(width 0.1)
				(type default)
			)
			(layer "F.Fab")
		)
		(fp_line
			(start 0.12065 -0.2794)
			(end 0.12065 -0.3048)
			(stroke
				(width 0.1)
				(type default)
			)
			(layer "F.Fab")
		)
		(fp_line
			(start -0.12065 -0.2794)
			(end 0.12065 -0.2794)
			(stroke
				(width 0.1)
				(type default)
			)
			(layer "F.Fab")
		)
		(fp_line
			(start 0.120396 0.2794)
			(end -0.12065 0.2794)
			(stroke
				(width 0.1)
				(type default)
			)
			(layer "F.Fab")
		)
		(fp_line
			(start -0.12065 0.2794)
			(end -0.12065 0.3048)
			(stroke
				(width 0.1)
				(type default)
			)
			(layer "F.Fab")
		)
		(fp_line
			(start 0.67945 0.3048)
			(end 0.120396 0.3048)
			(stroke
				(width 0.1)
				(type default)
			)
			(layer "F.Fab")
		)
		(fp_line
			(start 0.120396 0.3048)
			(end 0.120396 0.2794)
			(stroke
				(width 0.1)
				(type default)
			)
			(layer "F.Fab")
		)
		(fp_line
			(start -0.12065 0.3048)
			(end -0.67945 0.3048)
			(stroke
				(width 0.1)
				(type default)
			)
			(layer "F.Fab")
		)
		(fp_line
			(start -0.67945 0.3048)
			(end -0.67945 -0.305054)
			(stroke
				(width 0.1)
				(type default)
			)
			(layer "F.Fab")
		)
		(pad "1" smd circle
			(at -0.40005 0 90)
			(size 0 0)
			(layers "F.Cu" "F.Mask" "F.Paste")
			(net "P3V3_AUX")
		)
		(pad "2" smd circle
			(at 0.40005 0 90)
			(size 0 0)
			(layers "F.Cu" "F.Mask" "F.Paste")
			(net "PWRGD_P1V0_AUX_DELAY_R1")
		)
	)
)
